# S9S_MB_2U (Grand Teton) — schematic netlist excerpt (pin names and nets, part order shuffled) for the footprints in the layout excerpt that follows; sources: Cadence DE-HDL packaged netlist, KiCad conversion of 03242023_DA0F0TMBIJ0_F0T_Motherboard_J_brd_V01_OCP.brd

PR166  Q_RES  1K 1% EMPTY  pkg 0402LF  page 266 : A = PVCCIN_CPU0_VIN_CSNIN ; B = GND
PC195_P0_1  Q_CAP  22UF 16V 20% X6S  pkg C0805  page 275 : A = SW_P12V_PVCCINFAON_CPU0_FLT ; B = GND
PR294  Q_RES  2.2 1% CHIP  pkg 0402LF  page 287 : A = PVCCIN_CPU1_PVCC ; B = PVCCIN_CPU1_VDD5

(kicad_pcb
	(version 20260206)
	(generator "pcbnew")
	(generator_version "10.0")
	(general
		(thickness 1.6)
		(legacy_teardrops no)
	)
	(paper "A4")
	(title_block
		(title "03242023_DA0F0TMBIJ0_F0T_Motherboard_J_brd_V01_OCP.brd")
		(comment 1 "Grand Teton / footprints 4235-4237 of 6105")
	)
	(layers
		(0 "F.Cu" signal "TOP")
		(4 "In1.Cu" signal "GND")
		(6 "In2.Cu" signal "IN1")
		(8 "In3.Cu" signal "GND1")
		(10 "In4.Cu" signal "IN2")
		(12 "In5.Cu" signal "GND2")
		(14 "In6.Cu" signal "IN3")
		(16 "In7.Cu" signal "GND3")
		(18 "In8.Cu" signal "VCC")
		(20 "In9.Cu" signal "VCC1")
		(22 "In10.Cu" signal "GND4")
		(24 "In11.Cu" signal "IN4")
		(26 "In12.Cu" signal "GND5")
		(28 "In13.Cu" signal "IN5")
		(30 "In14.Cu" signal "GND6")
		(32 "In15.Cu" signal "IN6")
		(34 "In16.Cu" signal "GND7")
		(2 "B.Cu" signal "BOTTOM")
		(9 "F.Adhes" user "F.Adhesive")
		(11 "B.Adhes" user "B.Adhesive")
		(13 "F.Paste" user "Package Geometry/Pastemask Top")
		(15 "B.Paste" user "Package Geometry/Pastemask Bottom")
		(5 "F.SilkS" user "Ref Des/Silkscreen Top")
		(7 "B.SilkS" user "Ref Des/Silkscreen Bottom")
		(1 "F.Mask" user "Board Geometry/Soldermask Top")
		(3 "B.Mask" user "Board Geometry/Soldermask Bottom")
		(17 "Dwgs.User" user "User.Drawings")
		(19 "Cmts.User" user "User.Comments")
		(21 "Eco1.User" user "User.Eco1")
		(23 "Eco2.User" user "User.Eco2")
		(25 "Edge.Cuts" user "Board Geometry/Outline")
		(27 "Margin" user)
		(31 "F.CrtYd" user "Package Geometry/Place Bound Top")
		(29 "B.CrtYd" user "Package Geometry/Place Bound Bottom")
		(35 "F.Fab" user "Ref Des/Assembly Top")
		(33 "B.Fab" user "Ref Des/Assembly Bottom")
	)
	(footprint ""
		(layer "B.Cu")
		(at 359.56113 -360.847386)
		(property "Reference" "PR166"
			(at 0 0 0)
			(layer "B.SilkS")
			(hide yes)
			(effects
				(font
					(size 1.27 1.27)
				)
				(justify mirror)
			)
		)
		(property "Value" ""
			(at 0 0 0)
			(layer "B.Fab")
			(effects
				(font
					(size 1.27 1.27)
				)
				(justify mirror)
			)
		)
		(duplicate_pad_numbers_are_jumpers no)
		(fp_line
			(start -0.7874 -0.4064)
			(end -0.7874 0.4064)
			(stroke
				(width 0.1524)
				(type default)
			)
			(layer "B.SilkS")
		)
		(fp_line
			(start -0.7874 0.4064)
			(end 0.7874 0.4064)
			(stroke
				(width 0.1524)
				(type default)
			)
			(layer "B.SilkS")
		)
		(fp_line
			(start 0.7874 -0.4064)
			(end -0.7874 -0.4064)
			(stroke
				(width 0.1524)
				(type default)
			)
			(layer "B.SilkS")
		)
		(fp_line
			(start 0.7874 0.4064)
			(end 0.7874 -0.4064)
			(stroke
				(width 0.1524)
				(type default)
			)
			(layer "B.SilkS")
		)
		(fp_line
			(start -0.67945 -0.3048)
			(end -0.67945 0.3048)
			(stroke
				(width 0.1)
				(type default)
			)
			(layer "B.Fab")
		)
		(fp_line
			(start -0.67945 0.3048)
			(end -0.120396 0.3048)
			(stroke
				(width 0.1)
				(type default)
			)
			(layer "B.Fab")
		)
		(fp_line
			(start -0.12065 -0.3048)
			(end -0.67945 -0.3048)
			(stroke
				(width 0.1)
				(type default)
			)
			(layer "B.Fab")
		)
		(fp_line
			(start -0.12065 -0.2794)
			(end -0.12065 -0.3048)
			(stroke
				(width 0.1)
				(type default)
			)
			(layer "B.Fab")
		)
		(fp_line
			(start -0.120396 0.2794)
			(end 0.12065 0.2794)
			(stroke
				(width 0.1)
				(type default)
			)
			(layer "B.Fab")
		)
		(fp_line
			(start -0.120396 0.3048)
			(end -0.120396 0.2794)
			(stroke
				(width 0.1)
				(type default)
			)
			(layer "B.Fab")
		)
		(fp_line
			(start 0.12065 -0.305054)
			(end 0.12065 -0.2794)
			(stroke
				(width 0.1)
				(type default)
			)
			(layer "B.Fab")
		)
		(fp_line
			(start 0.12065 -0.2794)
			(end -0.12065 -0.2794)
			(stroke
				(width 0.1)
				(type default)
			)
			(layer "B.Fab")
		)
		(fp_line
			(start 0.12065 0.2794)
			(end 0.12065 0.3048)
			(stroke
				(width 0.1)
				(type default)
			)
			(layer "B.Fab")
		)
		(fp_line
			(start 0.12065 0.3048)
			(end 0.67945 0.3048)
			(stroke
				(width 0.1)
				(type default)
			)
			(layer "B.Fab")
		)
		(fp_line
			(start 0.67945 -0.305054)
			(end 0.12065 -0.305054)
			(stroke
				(width 0.1)
				(type default)
			)
			(layer "B.Fab")
		)
		(fp_line
			(start 0.67945 0.3048)
			(end 0.67945 -0.305054)
			(stroke
				(width 0.1)
				(type default)
			)
			(layer "B.Fab")
		)
		(pad "1" smd circle
			(at 0.40005 0 180)
			(size 0 0)
			(layers "B.Cu" "B.Mask" "B.Paste")
			(net "PVCCIN_CPU0_VIN_CSNIN")
		)
		(pad "2" smd circle
			(at -0.40005 0 180)
			(size 0 0)
			(layers "B.Cu" "B.Mask" "B.Paste")
			(net "GND")
		)
	)
	(footprint ""
		(layer "B.Cu")
		(at 416.02914 -167.56507)
		(property "Reference" "PC195_P0_1"
			(at 0 0 0)
			(layer "B.SilkS")
			(hide yes)
			(effects
				(font
					(size 1.27 1.27)
				)
				(justify mirror)
			)
		)
		(property "Value" ""
			(at 0 0 0)
			(layer "B.Fab")
			(effects
				(font
					(size 1.27 1.27)
				)
				(justify mirror)
			)
		)
		(duplicate_pad_numbers_are_jumpers no)
		(fp_line
			(start -1.524 -0.762)
			(end -1.524 0.762)
			(stroke
				(width 0.1524)
				(type default)
			)
			(layer "B.SilkS")
		)
		(fp_line
			(start -1.524 0.762)
			(end 1.524 0.762)
			(stroke
				(width 0.1524)
				(type default)
			)
			(layer "B.SilkS")
		)
		(fp_line
			(start 1.524 -0.762)
			(end -1.524 -0.762)
			(stroke
				(width 0.1524)
				(type default)
			)
			(layer "B.SilkS")
		)
		(fp_line
			(start 1.524 0.762)
			(end 1.524 -0.762)
			(stroke
				(width 0.1524)
				(type default)
			)
			(layer "B.SilkS")
		)
		(fp_line
			(start -1.1049 -0.724916)
			(end 1.1049 -0.724916)
			(stroke
				(width 0.1)
				(type default)
			)
			(layer "B.Fab")
		)
		(fp_line
			(start -1.1049 0.724916)
			(end -1.1049 -0.724916)
			(stroke
				(width 0.1)
				(type default)
			)
			(layer "B.Fab")
		)
		(fp_line
			(start 1.1049 -0.724916)
			(end 1.1049 0.724916)
			(stroke
				(width 0.1)
				(type default)
			)
			(layer "B.Fab")
		)
		(fp_line
			(start 1.1049 0.724916)
			(end -1.1049 0.724916)
			(stroke
				(width 0.1)
				(type default)
			)
			(layer "B.Fab")
		)
		(pad "1" smd rect
			(at 0.889 0)
			(size 1.016 1.27)
			(layers "B.Cu" "B.Mask" "B.Paste")
			(net "SW_P12V_PVCCINFAON_CPU0_FLT")
		)
		(pad "2" smd rect
			(at -0.889 0)
			(size 1.016 1.27)
			(layers "B.Cu" "B.Mask" "B.Paste")
			(net "GND")
		)
	)
	(footprint ""
		(layer "B.Cu")
		(at 127.257302 -338.098892 -90)
		(property "Reference" "PR294"
			(at 0 0 90)
			(layer "B.SilkS")
			(hide yes)
			(effects
				(font
					(size 1.27 1.27)
				)
				(justify mirror)
			)
		)
		(property "Value" ""
			(at 0 0 90)
			(layer "B.Fab")
			(effects
				(font
					(size 1.27 1.27)
				)
				(justify mirror)
			)
		)
		(duplicate_pad_numbers_are_jumpers no)
		(fp_line
			(start -0.7874 0.4064)
			(end 0.7874 0.4064)
			(stroke
				(width 0.1524)
				(type default)
			)
			(layer "B.SilkS")
		)
		(fp_line
			(start 0.7874 0.4064)
			(end 0.7874 -0.4064)
			(stroke
				(width 0.1524)
				(type default)
			)
			(layer "B.SilkS")
		)
		(fp_line
			(start -0.7874 -0.4064)
			(end -0.7874 0.4064)
			(stroke
				(width 0.1524)
				(type default)
			)
			(layer "B.SilkS")
		)
		(fp_line
			(start 0.7874 -0.4064)
			(end -0.7874 -0.4064)
			(stroke
				(width 0.1524)
				(type default)
			)
			(layer "B.SilkS")
		)
		(fp_line
			(start -0.67945 0.3048)
			(end -0.120396 0.3048)
			(stroke
				(width 0.1)
				(type default)
			)
			(layer "B.Fab")
		)
		(fp_line
			(start -0.120396 0.3048)
			(end -0.120396 0.2794)
			(stroke
				(width 0.1)
				(type default)
			)
			(layer "B.Fab")
		)
		(fp_line
			(start 0.12065 0.3048)
			(end 0.67945 0.3048)
			(stroke
				(width 0.1)
				(type default)
			)
			(layer "B.Fab")
		)
		(fp_line
			(start 0.67945 0.3048)
			(end 0.67945 -0.305054)
			(stroke
				(width 0.1)
				(type default)
			)
			(layer "B.Fab")
		)
		(fp_line
			(start -0.120396 0.2794)
			(end 0.12065 0.2794)
			(stroke
				(width 0.1)
				(type default)
			)
			(layer "B.Fab")
		)
		(fp_line
			(start 0.12065 0.2794)
			(end 0.12065 0.3048)
			(stroke
				(width 0.1)
				(type default)
			)
			(layer "B.Fab")
		)
		(fp_line
			(start -0.12065 -0.2794)
			(end -0.12065 -0.3048)
			(stroke
				(width 0.1)
				(type default)
			)
			(layer "B.Fab")
		)
		(fp_line
			(start 0.12065 -0.2794)
			(end -0.12065 -0.2794)
			(stroke
				(width 0.1)
				(type default)
			)
			(layer "B.Fab")
		)
		(fp_line
			(start -0.67945 -0.3048)
			(end -0.67945 0.3048)
			(stroke
				(width 0.1)
				(type default)
			)
			(layer "B.Fab")
		)
		(fp_line
			(start -0.12065 -0.3048)
			(end -0.67945 -0.3048)
			(stroke
				(width 0.1)
				(type default)
			)
			(layer "B.Fab")
		)
		(fp_line
			(start 0.12065 -0.305054)
			(end 0.12065 -0.2794)
			(stroke
				(width 0.1)
				(type default)
			)
			(layer "B.Fab")
		)
		(fp_line
			(start 0.67945 -0.305054)
			(end 0.12065 -0.305054)
			(stroke
				(width 0.1)
				(type default)
			)
			(layer "B.Fab")
		)
		(pad "1" smd circle
			(at 0.40005 0 90)
			(size 0 0)
			(layers "B.Cu" "B.Mask" "B.Paste")
			(net "PVCCIN_CPU1_PVCC")
		)
		(pad "2" smd circle
			(at -0.40005 0 90)
			(size 0 0)
			(layers "B.Cu" "B.Mask" "B.Paste")
			(net "PVCCIN_CPU1_VDD5")
		)
	)
)
